# T6G (Grand Teton) — schematic netlist excerpt (pin names and nets, part order shuffled) for the footprints in the layout excerpt that follows; sources: Cadence DE-HDL packaged netlist, KiCad conversion of 04192023_DAF0TMB3IC0_F0TG_MB_C_brd_V02_OCP.brd

R6803  Q_RES  10K 1% CHIP  pkg 0402LF  page 183 : A = FM_9ZXL045_P1_3_OE_N ; B = GND
R4161  Q_RES  100K 1% EMPTY  pkg 0402LF  page 124 : A = GPU_3V3IO_RSVD4 ; B = GND
R675  Q_RES  49.9 1% CHIP  pkg 0201LF  page 320 : A = SMB_RT_CPU1_P0_ROM_MUX_1D_SDA ; B = SMB_RT_CPU1_P0_ROM_MUX_1D_R_SDA

(kicad_pcb
	(version 20260206)
	(generator "pcbnew")
	(generator_version "10.0")
	(general
		(thickness 1.6)
		(legacy_teardrops no)
	)
	(paper "A4")
	(title_block
		(title "04192023_DAF0TMB3IC0_F0TG_MB_C_brd_V02_OCP.brd")
		(comment 1 "Grand Teton / footprints 2236-2238 of 8354")
	)
	(layers
		(0 "F.Cu" signal "TOP")
		(4 "In1.Cu" signal "GND")
		(6 "In2.Cu" signal "IN1")
		(8 "In3.Cu" signal "GND1")
		(10 "In4.Cu" signal "IN2")
		(12 "In5.Cu" signal "GND2")
		(14 "In6.Cu" signal "IN3")
		(16 "In7.Cu" signal "GND3")
		(18 "In8.Cu" signal "VCC")
		(20 "In9.Cu" signal "VCC1")
		(22 "In10.Cu" signal "GND4")
		(24 "In11.Cu" signal "IN4")
		(26 "In12.Cu" signal "GND5")
		(28 "In13.Cu" signal "IN5")
		(30 "In14.Cu" signal "GND6")
		(32 "In15.Cu" signal "IN6")
		(34 "In16.Cu" signal "GND7")
		(2 "B.Cu" signal "BOTTOM")
		(9 "F.Adhes" user "F.Adhesive")
		(11 "B.Adhes" user "B.Adhesive")
		(13 "F.Paste" user "Package Geometry/Pastemask Top")
		(15 "B.Paste" user "Package Geometry/Pastemask Bottom")
		(5 "F.SilkS" user "Ref Des/Silkscreen Top")
		(7 "B.SilkS" user "Ref Des/Silkscreen Bottom")
		(1 "F.Mask" user "Board Geometry/Soldermask Top")
		(3 "B.Mask" user "Board Geometry/Soldermask Bottom")
		(17 "Dwgs.User" user "User.Drawings")
		(19 "Cmts.User" user "User.Comments")
		(21 "Eco1.User" user "User.Eco1")
		(23 "Eco2.User" user "User.Eco2")
		(25 "Edge.Cuts" user "Board Geometry/Outline")
		(27 "Margin" user)
		(31 "F.CrtYd" user "Package Geometry/Place Bound Top")
		(29 "B.CrtYd" user "Package Geometry/Place Bound Bottom")
		(35 "F.Fab" user "Ref Des/Assembly Top")
		(33 "B.Fab" user "Ref Des/Assembly Bottom")
	)
	(footprint ""
		(layer "F.Cu")
		(at 42.33926 -379.56236)
		(property "Reference" "R675"
			(at 0 0 0)
			(layer "F.SilkS")
			(hide yes)
			(effects
				(font
					(size 1.27 1.27)
				)
			)
		)
		(property "Value" ""
			(at 0 0 0)
			(layer "F.Fab")
			(effects
				(font
					(size 1.27 1.27)
				)
			)
		)
		(duplicate_pad_numbers_are_jumpers no)
		(fp_line
			(start -0.32512 -0.175006)
			(end 0.32512 -0.175006)
			(stroke
				(width 0.1)
				(type default)
			)
			(layer "F.Fab")
		)
		(fp_line
			(start -0.32512 0.175006)
			(end -0.32512 -0.175006)
			(stroke
				(width 0.1)
				(type default)
			)
			(layer "F.Fab")
		)
		(fp_line
			(start 0.32512 -0.175006)
			(end 0.32512 0.175006)
			(stroke
				(width 0.1)
				(type default)
			)
			(layer "F.Fab")
		)
		(fp_line
			(start 0.32512 0.175006)
			(end -0.32512 0.175006)
			(stroke
				(width 0.1)
				(type default)
			)
			(layer "F.Fab")
		)
		(pad "1" smd rect
			(at -0.2667 0)
			(size 0.3048 0.381)
			(layers "F.Cu" "F.Mask" "F.Paste")
			(net "SMB_RT_CPU1_P0_ROM_MUX_1D_SDA")
		)
		(pad "2" smd rect
			(at 0.2667 0 180)
			(size 0.3048 0.381)
			(layers "F.Cu" "F.Mask" "F.Paste")
			(net "SMB_RT_CPU1_P0_ROM_MUX_1D_R_SDA")
		)
	)
	(footprint ""
		(layer "F.Cu")
		(at 438.056782 -439.12536 90)
		(property "Reference" "R4161"
			(at 0 0 90)
			(layer "F.SilkS")
			(hide yes)
			(effects
				(font
					(size 1.27 1.27)
				)
			)
		)
		(property "Value" ""
			(at 0 0 90)
			(layer "F.Fab")
			(effects
				(font
					(size 1.27 1.27)
				)
			)
		)
		(duplicate_pad_numbers_are_jumpers no)
		(fp_line
			(start 0.7874 -0.4064)
			(end 0.7874 0.4064)
			(stroke
				(width 0.1524)
				(type default)
			)
			(layer "F.SilkS")
		)
		(fp_line
			(start -0.7874 -0.4064)
			(end 0.7874 -0.4064)
			(stroke
				(width 0.1524)
				(type default)
			)
			(layer "F.SilkS")
		)
		(fp_line
			(start 0.7874 0.4064)
			(end -0.7874 0.4064)
			(stroke
				(width 0.1524)
				(type default)
			)
			(layer "F.SilkS")
		)
		(fp_line
			(start -0.7874 0.4064)
			(end -0.7874 -0.4064)
			(stroke
				(width 0.1524)
				(type default)
			)
			(layer "F.SilkS")
		)
		(fp_line
			(start -0.12065 -0.305054)
			(end -0.12065 -0.2794)
			(stroke
				(width 0.1)
				(type default)
			)
			(layer "F.Fab")
		)
		(fp_line
			(start -0.67945 -0.305054)
			(end -0.12065 -0.305054)
			(stroke
				(width 0.1)
				(type default)
			)
			(layer "F.Fab")
		)
		(fp_line
			(start 0.67945 -0.3048)
			(end 0.67945 0.3048)
			(stroke
				(width 0.1)
				(type default)
			)
			(layer "F.Fab")
		)
		(fp_line
			(start 0.12065 -0.3048)
			(end 0.67945 -0.3048)
			(stroke
				(width 0.1)
				(type default)
			)
			(layer "F.Fab")
		)
		(fp_line
			(start 0.12065 -0.2794)
			(end 0.12065 -0.3048)
			(stroke
				(width 0.1)
				(type default)
			)
			(layer "F.Fab")
		)
		(fp_line
			(start -0.12065 -0.2794)
			(end 0.12065 -0.2794)
			(stroke
				(width 0.1)
				(type default)
			)
			(layer "F.Fab")
		)
		(fp_line
			(start 0.120396 0.2794)
			(end -0.12065 0.2794)
			(stroke
				(width 0.1)
				(type default)
			)
			(layer "F.Fab")
		)
		(fp_line
			(start -0.12065 0.2794)
			(end -0.12065 0.3048)
			(stroke
				(width 0.1)
				(type default)
			)
			(layer "F.Fab")
		)
		(fp_line
			(start 0.67945 0.3048)
			(end 0.120396 0.3048)
			(stroke
				(width 0.1)
				(type default)
			)
			(layer "F.Fab")
		)
		(fp_line
			(start 0.120396 0.3048)
			(end 0.120396 0.2794)
			(stroke
				(width 0.1)
				(type default)
			)
			(layer "F.Fab")
		)
		(fp_line
			(start -0.12065 0.3048)
			(end -0.67945 0.3048)
			(stroke
				(width 0.1)
				(type default)
			)
			(layer "F.Fab")
		)
		(fp_line
			(start -0.67945 0.3048)
			(end -0.67945 -0.305054)
			(stroke
				(width 0.1)
				(type default)
			)
			(layer "F.Fab")
		)
		(pad "1" smd circle
			(at -0.40005 0 90)
			(size 0 0)
			(layers "F.Cu" "F.Mask" "F.Paste")
			(net "GPU_3V3IO_RSVD4")
		)
		(pad "2" smd circle
			(at 0.40005 0 90)
			(size 0 0)
			(layers "F.Cu" "F.Mask" "F.Paste")
			(net "GND")
		)
	)
	(footprint ""
		(layer "F.Cu")
		(at 111.76 -407.4668)
		(property "Reference" "R6803"
			(at 0 0 0)
			(layer "F.SilkS")
			(hide yes)
			(effects
				(font
					(size 1.27 1.27)
				)
			)
		)
		(property "Value" ""
			(at 0 0 0)
			(layer "F.Fab")
			(effects
				(font
					(size 1.27 1.27)
				)
			)
		)
		(duplicate_pad_numbers_are_jumpers no)
		(fp_line
			(start -0.7874 -0.4064)
			(end 0.7874 -0.4064)
			(stroke
				(width 0.1524)
				(type default)
			)
			(layer "F.SilkS")
		)
		(fp_line
			(start -0.7874 0.4064)
			(end -0.7874 -0.4064)
			(stroke
				(width 0.1524)
				(type default)
			)
			(layer "F.SilkS")
		)
		(fp_line
			(start 0.7874 -0.4064)
			(end 0.7874 0.4064)
			(stroke
				(width 0.1524)
				(type default)
			)
			(layer "F.SilkS")
		)
		(fp_line
			(start 0.7874 0.4064)
			(end -0.7874 0.4064)
			(stroke
				(width 0.1524)
				(type default)
			)
			(layer "F.SilkS")
		)
		(fp_line
			(start -0.67945 -0.305054)
			(end -0.12065 -0.305054)
			(stroke
				(width 0.1)
				(type default)
			)
			(layer "F.Fab")
		)
		(fp_line
			(start -0.67945 0.3048)
			(end -0.67945 -0.305054)
			(stroke
				(width 0.1)
				(type default)
			)
			(layer "F.Fab")
		)
		(fp_line
			(start -0.12065 -0.305054)
			(end -0.12065 -0.2794)
			(stroke
				(width 0.1)
				(type default)
			)
			(layer "F.Fab")
		)
		(fp_line
			(start -0.12065 -0.2794)
			(end 0.12065 -0.2794)
			(stroke
				(width 0.1)
				(type default)
			)
			(layer "F.Fab")
		)
		(fp_line
			(start -0.12065 0.2794)
			(end -0.12065 0.3048)
			(stroke
				(width 0.1)
				(type default)
			)
			(layer "F.Fab")
		)
		(fp_line
			(start -0.12065 0.3048)
			(end -0.67945 0.3048)
			(stroke
				(width 0.1)
				(type default)
			)
			(layer "F.Fab")
		)
		(fp_line
			(start 0.120396 0.2794)
			(end -0.12065 0.2794)
			(stroke
				(width 0.1)
				(type default)
			)
			(layer "F.Fab")
		)
		(fp_line
			(start 0.120396 0.3048)
			(end 0.120396 0.2794)
			(stroke
				(width 0.1)
				(type default)
			)
			(layer "F.Fab")
		)
		(fp_line
			(start 0.12065 -0.3048)
			(end 0.67945 -0.3048)
			(stroke
				(width 0.1)
				(type default)
			)
			(layer "F.Fab")
		)
		(fp_line
			(start 0.12065 -0.2794)
			(end 0.12065 -0.3048)
			(stroke
				(width 0.1)
				(type default)
			)
			(layer "F.Fab")
		)
		(fp_line
			(start 0.67945 -0.3048)
			(end 0.67945 0.3048)
			(stroke
				(width 0.1)
				(type default)
			)
			(layer "F.Fab")
		)
		(fp_line
			(start 0.67945 0.3048)
			(end 0.120396 0.3048)
			(stroke
				(width 0.1)
				(type default)
			)
			(layer "F.Fab")
		)
		(pad "1" smd circle
			(at -0.40005 0)
			(size 0 0)
			(layers "F.Cu" "F.Mask" "F.Paste")
			(net "FM_9ZXL045_P1_3_OE_N")
		)
		(pad "2" smd circle
			(at 0.40005 0)
			(size 0 0)
			(layers "F.Cu" "F.Mask" "F.Paste")
			(net "GND")
		)
	)
)
